# S9S_MB_2U (Grand Teton) — schematic netlist excerpt (pin names and nets, part order shuffled) for the footprints in the layout excerpt that follows; sources: Cadence DE-HDL packaged netlist, KiCad conversion of 03242023_DA0F0TMBIJ0_F0T_Motherboard_J_brd_V01_OCP.brd

R90  Q_RES  240 1% EMPTY  pkg 0402LF  page 126 : A = PVNN_TERM_CPU1 ; B = PU_CPU1_UPI0_AC_COUPLING
R1554  Q_RES  10K 1% CHIP  pkg 0402LF  page 204 : A = P3V3_AUX ; B = FM_ME_AUTHN_FAIL

(kicad_pcb
	(version 20260206)
	(generator "pcbnew")
	(generator_version "10.0")
	(general
		(thickness 1.6)
		(legacy_teardrops no)
	)
	(paper "A4")
	(title_block
		(title "03242023_DA0F0TMBIJ0_F0T_Motherboard_J_brd_V01_OCP.brd")
		(comment 1 "Grand Teton / footprints 5893-5894 of 6105")
	)
	(layers
		(0 "F.Cu" signal "TOP")
		(4 "In1.Cu" signal "GND")
		(6 "In2.Cu" signal "IN1")
		(8 "In3.Cu" signal "GND1")
		(10 "In4.Cu" signal "IN2")
		(12 "In5.Cu" signal "GND2")
		(14 "In6.Cu" signal "IN3")
		(16 "In7.Cu" signal "GND3")
		(18 "In8.Cu" signal "VCC")
		(20 "In9.Cu" signal "VCC1")
		(22 "In10.Cu" signal "GND4")
		(24 "In11.Cu" signal "IN4")
		(26 "In12.Cu" signal "GND5")
		(28 "In13.Cu" signal "IN5")
		(30 "In14.Cu" signal "GND6")
		(32 "In15.Cu" signal "IN6")
		(34 "In16.Cu" signal "GND7")
		(2 "B.Cu" signal "BOTTOM")
		(9 "F.Adhes" user "F.Adhesive")
		(11 "B.Adhes" user "B.Adhesive")
		(13 "F.Paste" user "Package Geometry/Pastemask Top")
		(15 "B.Paste" user "Package Geometry/Pastemask Bottom")
		(5 "F.SilkS" user "Ref Des/Silkscreen Top")
		(7 "B.SilkS" user "Ref Des/Silkscreen Bottom")
		(1 "F.Mask" user "Board Geometry/Soldermask Top")
		(3 "B.Mask" user "Board Geometry/Soldermask Bottom")
		(17 "Dwgs.User" user "User.Drawings")
		(19 "Cmts.User" user "User.Comments")
		(21 "Eco1.User" user "User.Eco1")
		(23 "Eco2.User" user "User.Eco2")
		(25 "Edge.Cuts" user "Board Geometry/Outline")
		(27 "Margin" user)
		(31 "F.CrtYd" user "Package Geometry/Place Bound Top")
		(29 "B.CrtYd" user "Package Geometry/Place Bound Bottom")
		(35 "F.Fab" user "Ref Des/Assembly Top")
		(33 "B.Fab" user "Ref Des/Assembly Bottom")
	)
	(footprint ""
		(layer "B.Cu")
		(at 77.368908 -185.926476 -90)
		(property "Reference" "R90"
			(at 0 0 90)
			(layer "B.SilkS")
			(hide yes)
			(effects
				(font
					(size 1.27 1.27)
				)
				(justify mirror)
			)
		)
		(property "Value" ""
			(at 0 0 90)
			(layer "B.Fab")
			(effects
				(font
					(size 1.27 1.27)
				)
				(justify mirror)
			)
		)
		(duplicate_pad_numbers_are_jumpers no)
		(fp_line
			(start -0.7874 0.4064)
			(end 0.7874 0.4064)
			(stroke
				(width 0.1524)
				(type default)
			)
			(layer "B.SilkS")
		)
		(fp_line
			(start 0.7874 0.4064)
			(end 0.7874 -0.4064)
			(stroke
				(width 0.1524)
				(type default)
			)
			(layer "B.SilkS")
		)
		(fp_line
			(start -0.7874 -0.4064)
			(end -0.7874 0.4064)
			(stroke
				(width 0.1524)
				(type default)
			)
			(layer "B.SilkS")
		)
		(fp_line
			(start 0.7874 -0.4064)
			(end -0.7874 -0.4064)
			(stroke
				(width 0.1524)
				(type default)
			)
			(layer "B.SilkS")
		)
		(fp_line
			(start -0.67945 0.3048)
			(end -0.120396 0.3048)
			(stroke
				(width 0.1)
				(type default)
			)
			(layer "B.Fab")
		)
		(fp_line
			(start -0.120396 0.3048)
			(end -0.120396 0.2794)
			(stroke
				(width 0.1)
				(type default)
			)
			(layer "B.Fab")
		)
		(fp_line
			(start 0.12065 0.3048)
			(end 0.67945 0.3048)
			(stroke
				(width 0.1)
				(type default)
			)
			(layer "B.Fab")
		)
		(fp_line
			(start 0.67945 0.3048)
			(end 0.67945 -0.305054)
			(stroke
				(width 0.1)
				(type default)
			)
			(layer "B.Fab")
		)
		(fp_line
			(start -0.120396 0.2794)
			(end 0.12065 0.2794)
			(stroke
				(width 0.1)
				(type default)
			)
			(layer "B.Fab")
		)
		(fp_line
			(start 0.12065 0.2794)
			(end 0.12065 0.3048)
			(stroke
				(width 0.1)
				(type default)
			)
			(layer "B.Fab")
		)
		(fp_line
			(start -0.12065 -0.2794)
			(end -0.12065 -0.3048)
			(stroke
				(width 0.1)
				(type default)
			)
			(layer "B.Fab")
		)
		(fp_line
			(start 0.12065 -0.2794)
			(end -0.12065 -0.2794)
			(stroke
				(width 0.1)
				(type default)
			)
			(layer "B.Fab")
		)
		(fp_line
			(start -0.67945 -0.3048)
			(end -0.67945 0.3048)
			(stroke
				(width 0.1)
				(type default)
			)
			(layer "B.Fab")
		)
		(fp_line
			(start -0.12065 -0.3048)
			(end -0.67945 -0.3048)
			(stroke
				(width 0.1)
				(type default)
			)
			(layer "B.Fab")
		)
		(fp_line
			(start 0.12065 -0.305054)
			(end 0.12065 -0.2794)
			(stroke
				(width 0.1)
				(type default)
			)
			(layer "B.Fab")
		)
		(fp_line
			(start 0.67945 -0.305054)
			(end 0.12065 -0.305054)
			(stroke
				(width 0.1)
				(type default)
			)
			(layer "B.Fab")
		)
		(pad "1" smd circle
			(at 0.40005 0 90)
			(size 0 0)
			(layers "B.Cu" "B.Mask" "B.Paste")
			(net "PVNN_TERM_CPU1")
		)
		(pad "2" smd circle
			(at -0.40005 0 90)
			(size 0 0)
			(layers "B.Cu" "B.Mask" "B.Paste")
			(net "PU_CPU1_UPI0_AC_COUPLING")
		)
	)
	(footprint ""
		(layer "B.Cu")
		(at 341.00135 -37.574728 -90)
		(property "Reference" "R1554"
			(at 0 0 90)
			(layer "B.SilkS")
			(hide yes)
			(effects
				(font
					(size 1.27 1.27)
				)
				(justify mirror)
			)
		)
		(property "Value" ""
			(at 0 0 90)
			(layer "B.Fab")
			(effects
				(font
					(size 1.27 1.27)
				)
				(justify mirror)
			)
		)
		(duplicate_pad_numbers_are_jumpers no)
		(fp_line
			(start -0.7874 0.4064)
			(end 0.7874 0.4064)
			(stroke
				(width 0.1524)
				(type default)
			)
			(layer "B.SilkS")
		)
		(fp_line
			(start 0.7874 0.4064)
			(end 0.7874 -0.4064)
			(stroke
				(width 0.1524)
				(type default)
			)
			(layer "B.SilkS")
		)
		(fp_line
			(start -0.7874 -0.4064)
			(end -0.7874 0.4064)
			(stroke
				(width 0.1524)
				(type default)
			)
			(layer "B.SilkS")
		)
		(fp_line
			(start 0.7874 -0.4064)
			(end -0.7874 -0.4064)
			(stroke
				(width 0.1524)
				(type default)
			)
			(layer "B.SilkS")
		)
		(fp_line
			(start -0.67945 0.3048)
			(end -0.120396 0.3048)
			(stroke
				(width 0.1)
				(type default)
			)
			(layer "B.Fab")
		)
		(fp_line
			(start -0.120396 0.3048)
			(end -0.120396 0.2794)
			(stroke
				(width 0.1)
				(type default)
			)
			(layer "B.Fab")
		)
		(fp_line
			(start 0.12065 0.3048)
			(end 0.67945 0.3048)
			(stroke
				(width 0.1)
				(type default)
			)
			(layer "B.Fab")
		)
		(fp_line
			(start 0.67945 0.3048)
			(end 0.67945 -0.305054)
			(stroke
				(width 0.1)
				(type default)
			)
			(layer "B.Fab")
		)
		(fp_line
			(start -0.120396 0.2794)
			(end 0.12065 0.2794)
			(stroke
				(width 0.1)
				(type default)
			)
			(layer "B.Fab")
		)
		(fp_line
			(start 0.12065 0.2794)
			(end 0.12065 0.3048)
			(stroke
				(width 0.1)
				(type default)
			)
			(layer "B.Fab")
		)
		(fp_line
			(start -0.12065 -0.2794)
			(end -0.12065 -0.3048)
			(stroke
				(width 0.1)
				(type default)
			)
			(layer "B.Fab")
		)
		(fp_line
			(start 0.12065 -0.2794)
			(end -0.12065 -0.2794)
			(stroke
				(width 0.1)
				(type default)
			)
			(layer "B.Fab")
		)
		(fp_line
			(start -0.67945 -0.3048)
			(end -0.67945 0.3048)
			(stroke
				(width 0.1)
				(type default)
			)
			(layer "B.Fab")
		)
		(fp_line
			(start -0.12065 -0.3048)
			(end -0.67945 -0.3048)
			(stroke
				(width 0.1)
				(type default)
			)
			(layer "B.Fab")
		)
		(fp_line
			(start 0.12065 -0.305054)
			(end 0.12065 -0.2794)
			(stroke
				(width 0.1)
				(type default)
			)
			(layer "B.Fab")
		)
		(fp_line
			(start 0.67945 -0.305054)
			(end 0.12065 -0.305054)
			(stroke
				(width 0.1)
				(type default)
			)
			(layer "B.Fab")
		)
		(pad "1" smd circle
			(at 0.40005 0 90)
			(size 0 0)
			(layers "B.Cu" "B.Mask" "B.Paste")
			(net "P3V3_AUX")
		)
		(pad "2" smd circle
			(at -0.40005 0 90)
			(size 0 0)
			(layers "B.Cu" "B.Mask" "B.Paste")
			(net "FM_ME_AUTHN_FAIL")
		)
	)
)
